# BASEBOARD_FAB2 (Tioga Pass) — schematic netlist excerpt (pin names and nets, part order shuffled) for the footprints in the layout excerpt that follows; sources: Cadence DE-HDL packaged netlist, KiCad conversion of Wiwynn_Tioga_Pass_MB.brd

R9M18  RES  240 1.0% CHIP  pkg 0402  page 163 : A = PVCCIO_CPU1 ; B = SMB_CPU1_PE_HP_GTL_R_SDA
R25W179  RES  1.00K 1% CHIP  pkg 0402  page 255 : A = P3V3_STBY ; B = XDP_PRESENT_N
R8E26  RES  0.0 5% CHIP  pkg 0402  page 142 : A = FM_PE_OCP_WAKE_N ; B = FM_ALL_WAKE_N

(kicad_pcb
	(version 20260206)
	(generator "pcbnew")
	(generator_version "10.0")
	(general
		(thickness 1.6)
		(legacy_teardrops no)
	)
	(paper "A4")
	(title_block
		(title "Wiwynn_Tioga_Pass_MB.brd")
		(comment 1 "Tioga Pass / footprints 4507-4509 of 4770")
	)
	(layers
		(0 "F.Cu" signal "TOP")
		(4 "In1.Cu" signal "L2GND")
		(6 "In2.Cu" signal "L3")
		(8 "In3.Cu" signal "L4GND")
		(10 "In4.Cu" signal "L5")
		(12 "In5.Cu" signal "L6GND")
		(14 "In6.Cu" signal "L7VCC")
		(16 "In7.Cu" signal "L8VCC")
		(18 "In8.Cu" signal "L9GND")
		(20 "In9.Cu" signal "L10")
		(22 "In10.Cu" signal "L11GND")
		(24 "In11.Cu" signal "L12")
		(26 "In12.Cu" signal "L13GND")
		(2 "B.Cu" signal "BOTTOM")
		(9 "F.Adhes" user "F.Adhesive")
		(11 "B.Adhes" user "B.Adhesive")
		(13 "F.Paste" user "Package Geometry/Pastemask Top")
		(15 "B.Paste" user "Package Geometry/Pastemask Bottom")
		(5 "F.SilkS" user "Ref Des/Silkscreen Top")
		(7 "B.SilkS" user "Ref Des/Silkscreen Bottom")
		(1 "F.Mask" user "Board Geometry/Soldermask Top")
		(3 "B.Mask" user "Board Geometry/Soldermask Bottom")
		(17 "Dwgs.User" user "User.Drawings")
		(19 "Cmts.User" user "User.Comments")
		(21 "Eco1.User" user "User.Eco1")
		(23 "Eco2.User" user "User.Eco2")
		(25 "Edge.Cuts" user "Board Geometry/Outline")
		(27 "Margin" user)
		(31 "F.CrtYd" user "Package Geometry/Place Bound Top")
		(29 "B.CrtYd" user "Package Geometry/Place Bound Bottom")
		(35 "F.Fab" user "Ref Des/Assembly Top")
		(33 "B.Fab" user "Ref Des/Assembly Bottom")
	)
	(footprint ""
		(layer "B.Cu")
		(at 482.65969 -58.831988 -90)
		(property "Reference" "R8E26"
			(at 0 0 90)
			(layer "B.SilkS")
			(hide yes)
			(effects
				(font
					(size 1.27 1.27)
				)
				(justify mirror)
			)
		)
		(property "Value" ""
			(at 0 0 90)
			(layer "B.Fab")
			(effects
				(font
					(size 1.27 1.27)
				)
				(justify mirror)
			)
		)
		(duplicate_pad_numbers_are_jumpers no)
		(fp_poly
			(pts
				(xy 0.2794 -0.1016) (xy -0.2794 -0.1016) (xy -0.2794 0.9906) (xy 0.2794 0.9906)
			)
			(stroke
				(width 0)
				(type default)
			)
			(fill no)
			(layer "B.CrtYd")
		)
		(fp_line
			(start -0.2794 0.9906)
			(end -0.2794 -0.1016)
			(stroke
				(width 0.1)
				(type default)
			)
			(layer "B.Fab")
		)
		(fp_line
			(start 0.2794 0.9906)
			(end -0.2794 0.9906)
			(stroke
				(width 0.1)
				(type default)
			)
			(layer "B.Fab")
		)
		(fp_line
			(start -0.2794 -0.1016)
			(end 0.2794 -0.1016)
			(stroke
				(width 0.1)
				(type default)
			)
			(layer "B.Fab")
		)
		(fp_line
			(start 0.2794 -0.1016)
			(end 0.2794 0.9906)
			(stroke
				(width 0.1)
				(type default)
			)
			(layer "B.Fab")
		)
		(pad "1" smd rect
			(at 0 0 90)
			(size 0.508 0.508)
			(layers "B.Cu" "B.Mask" "B.Paste")
			(net "FM_PE_OCP_WAKE_N")
		)
		(pad "2" smd rect
			(at 0 0.889 90)
			(size 0.508 0.508)
			(layers "B.Cu" "B.Mask" "B.Paste")
			(net "FM_ALL_WAKE_N")
		)
		(zone
			(layer "B.Cu")
			(hatch none 0.5)
			(connect_pads
				(clearance 0)
			)
			(min_thickness 0.25)
			(keepout
				(tracks not_allowed)
				(vias allowed)
				(pads allowed)
				(copperpour not_allowed)
				(footprints allowed)
			)
			(placement
				(enabled no)
				(sheetname "")
			)
			(fill
				(thermal_gap 0.5)
				(thermal_bridge_width 0.5)
				(island_removal_mode 0)
			)
			(polygon
				(pts
					(xy 482.02469 -58.577988) (xy 482.02469 -59.085988) (xy 482.40569 -59.085988) (xy 482.40569 -58.577988)
				)
			)
		)
		(zone
			(layer "B.Cu")
			(hatch none 0.5)
			(connect_pads
				(clearance 0)
			)
			(min_thickness 0.25)
			(keepout
				(tracks allowed)
				(vias not_allowed)
				(pads allowed)
				(copperpour not_allowed)
				(footprints allowed)
			)
			(placement
				(enabled no)
				(sheetname "")
			)
			(fill
				(thermal_gap 0.5)
				(thermal_bridge_width 0.5)
				(island_removal_mode 0)
			)
			(polygon
				(pts
					(xy 482.40569 -58.577988) (xy 482.40569 -59.085988) (xy 482.02469 -59.085988) (xy 482.02469 -58.577988)
				)
			)
		)
	)
	(footprint ""
		(layer "B.Cu")
		(at 446.292478 -152.855168)
		(property "Reference" "R25W179"
			(at 0.8382 -0.67818 0)
			(unlocked yes)
			(layer "B.SilkS")
			(effects
				(font
					(size 0.4064 0.254)
					(thickness 0.1524)
				)
				(justify left mirror)
			)
		)
		(property "Value" ""
			(at 0 0 0)
			(layer "B.Fab")
			(effects
				(font
					(size 1.27 1.27)
				)
				(justify mirror)
			)
		)
		(duplicate_pad_numbers_are_jumpers no)
		(fp_poly
			(pts
				(xy 0.2794 -0.1016) (xy -0.2794 -0.1016) (xy -0.2794 0.9906) (xy 0.2794 0.9906)
			)
			(stroke
				(width 0)
				(type default)
			)
			(fill no)
			(layer "B.CrtYd")
		)
		(fp_line
			(start -0.2794 -0.1016)
			(end 0.2794 -0.1016)
			(stroke
				(width 0.1)
				(type default)
			)
			(layer "B.Fab")
		)
		(fp_line
			(start -0.2794 0.9906)
			(end -0.2794 -0.1016)
			(stroke
				(width 0.1)
				(type default)
			)
			(layer "B.Fab")
		)
		(fp_line
			(start 0.2794 -0.1016)
			(end 0.2794 0.9906)
			(stroke
				(width 0.1)
				(type default)
			)
			(layer "B.Fab")
		)
		(fp_line
			(start 0.2794 0.9906)
			(end -0.2794 0.9906)
			(stroke
				(width 0.1)
				(type default)
			)
			(layer "B.Fab")
		)
		(pad "1" smd rect
			(at 0 0 180)
			(size 0.508 0.508)
			(layers "B.Cu" "B.Mask" "B.Paste")
			(net "P3V3_STBY")
		)
		(pad "2" smd rect
			(at 0 0.889 180)
			(size 0.508 0.508)
			(layers "B.Cu" "B.Mask" "B.Paste")
			(net "XDP_PRESENT_N")
		)
		(zone
			(layer "B.Cu")
			(hatch none 0.5)
			(connect_pads
				(clearance 0)
			)
			(min_thickness 0.25)
			(keepout
				(tracks allowed)
				(vias not_allowed)
				(pads allowed)
				(copperpour not_allowed)
				(footprints allowed)
			)
			(placement
				(enabled no)
				(sheetname "")
			)
			(fill
				(thermal_gap 0.5)
				(thermal_bridge_width 0.5)
				(island_removal_mode 0)
			)
			(polygon
				(pts
					(xy 446.546478 -152.601168) (xy 446.038478 -152.601168) (xy 446.038478 -152.220168) (xy 446.546478 -152.220168)
				)
			)
		)
		(zone
			(layer "B.Cu")
			(hatch none 0.5)
			(connect_pads
				(clearance 0)
			)
			(min_thickness 0.25)
			(keepout
				(tracks not_allowed)
				(vias allowed)
				(pads allowed)
				(copperpour not_allowed)
				(footprints allowed)
			)
			(placement
				(enabled no)
				(sheetname "")
			)
			(fill
				(thermal_gap 0.5)
				(thermal_bridge_width 0.5)
				(island_removal_mode 0)
			)
			(polygon
				(pts
					(xy 446.546478 -152.220168) (xy 446.038478 -152.220168) (xy 446.038478 -152.601168) (xy 446.546478 -152.601168)
				)
			)
		)
	)
	(footprint ""
		(layer "B.Cu")
		(at -2.20726 -117.89156)
		(property "Reference" "R9M18"
			(at 0 0 0)
			(layer "B.SilkS")
			(hide yes)
			(effects
				(font
					(size 1.27 1.27)
				)
				(justify mirror)
			)
		)
		(property "Value" ""
			(at 0 0 0)
			(layer "B.Fab")
			(effects
				(font
					(size 1.27 1.27)
				)
				(justify mirror)
			)
		)
		(duplicate_pad_numbers_are_jumpers no)
		(fp_rect
			(start -0.2794 0.9906)
			(end 0.2794 -0.1016)
			(stroke
				(width 0)
				(type default)
			)
			(fill no)
			(layer "B.CrtYd")
		)
		(fp_line
			(start -0.2794 -0.1016)
			(end 0.2794 -0.1016)
			(stroke
				(width 0.1)
				(type default)
			)
			(layer "B.Fab")
		)
		(fp_line
			(start -0.2794 0.9906)
			(end -0.2794 -0.1016)
			(stroke
				(width 0.1)
				(type default)
			)
			(layer "B.Fab")
		)
		(fp_line
			(start 0.2794 -0.1016)
			(end 0.2794 0.9906)
			(stroke
				(width 0.1)
				(type default)
			)
			(layer "B.Fab")
		)
		(fp_line
			(start 0.2794 0.9906)
			(end -0.2794 0.9906)
			(stroke
				(width 0.1)
				(type default)
			)
			(layer "B.Fab")
		)
		(pad "1" smd rect
			(at 0 0 180)
			(size 0.508 0.508)
			(layers "B.Cu" "B.Mask" "B.Paste")
			(net "PVCCIO_CPU1")
		)
		(pad "2" smd rect
			(at 0 0.889 180)
			(size 0.508 0.508)
			(layers "B.Cu" "B.Mask" "B.Paste")
			(net "SMB_CPU1_PE_HP_GTL_R_SDA")
		)
		(zone
			(layer "B.Cu")
			(hatch none 0.5)
			(connect_pads
				(clearance 0)
			)
			(min_thickness 0.25)
			(keepout
				(tracks not_allowed)
				(vias allowed)
				(pads allowed)
				(copperpour not_allowed)
				(footprints allowed)
			)
			(placement
				(enabled no)
				(sheetname "")
			)
			(fill
				(thermal_gap 0.5)
				(thermal_bridge_width 0.5)
				(island_removal_mode 0)
			)
			(polygon
				(pts
					(xy -2.46126 -117.25656) (xy -1.95326 -117.25656) (xy -1.95326 -117.63756) (xy -2.46126 -117.63756)
				)
			)
		)
		(zone
			(layer "B.Cu")
			(hatch none 0.5)
			(connect_pads
				(clearance 0)
			)
			(min_thickness 0.25)
			(keepout
				(tracks allowed)
				(vias not_allowed)
				(pads allowed)
				(copperpour not_allowed)
				(footprints allowed)
			)
			(placement
				(enabled no)
				(sheetname "")
			)
			(fill
				(thermal_gap 0.5)
				(thermal_bridge_width 0.5)
				(island_removal_mode 0)
			)
			(polygon
				(pts
					(xy -2.46126 -117.25656) (xy -1.95326 -117.25656) (xy -1.95326 -117.63756) (xy -2.46126 -117.63756)
				)
			)
		)
	)
)
